# S9S_MB_2U (Grand Teton) — schematic netlist excerpt (pin names and nets, part order shuffled) for the footprints in the layout excerpt that follows; sources: Cadence DE-HDL packaged netlist, KiCad conversion of 03242023_DA0F0TMBIJ0_F0T_Motherboard_J_brd_V01_OCP.brd

R2346  Q_RES  4.7K 5% CHIP  pkg 0402LF  page 213 : A = P3V3_AUX ; B = PWRGD_P5V_AUX_R2
C946  Q_CAP_DIFFBUS  DIFF BUS_0.22UF 6.3V 20% X6S  pkg C0201  page 173 : \1\ = P5E_CPU0_PE2_TX_C_DN<9> ; \2\ = P5E_CPU0_PE2_TX_DN<9>
R3033  Q_RES  0 5% CHIP  pkg 0402LF  page 151 : A = UART_BMC_BIC_RX ; B = UART_BMC_BIC_R_RX

(kicad_pcb
	(version 20260206)
	(generator "pcbnew")
	(generator_version "10.0")
	(general
		(thickness 1.6)
		(legacy_teardrops no)
	)
	(paper "A4")
	(title_block
		(title "03242023_DA0F0TMBIJ0_F0T_Motherboard_J_brd_V01_OCP.brd")
		(comment 1 "Grand Teton / footprints 2558-2560 of 6105")
	)
	(layers
		(0 "F.Cu" signal "TOP")
		(4 "In1.Cu" signal "GND")
		(6 "In2.Cu" signal "IN1")
		(8 "In3.Cu" signal "GND1")
		(10 "In4.Cu" signal "IN2")
		(12 "In5.Cu" signal "GND2")
		(14 "In6.Cu" signal "IN3")
		(16 "In7.Cu" signal "GND3")
		(18 "In8.Cu" signal "VCC")
		(20 "In9.Cu" signal "VCC1")
		(22 "In10.Cu" signal "GND4")
		(24 "In11.Cu" signal "IN4")
		(26 "In12.Cu" signal "GND5")
		(28 "In13.Cu" signal "IN5")
		(30 "In14.Cu" signal "GND6")
		(32 "In15.Cu" signal "IN6")
		(34 "In16.Cu" signal "GND7")
		(2 "B.Cu" signal "BOTTOM")
		(9 "F.Adhes" user "F.Adhesive")
		(11 "B.Adhes" user "B.Adhesive")
		(13 "F.Paste" user "Package Geometry/Pastemask Top")
		(15 "B.Paste" user "Package Geometry/Pastemask Bottom")
		(5 "F.SilkS" user "Ref Des/Silkscreen Top")
		(7 "B.SilkS" user "Ref Des/Silkscreen Bottom")
		(1 "F.Mask" user "Board Geometry/Soldermask Top")
		(3 "B.Mask" user "Board Geometry/Soldermask Bottom")
		(17 "Dwgs.User" user "User.Drawings")
		(19 "Cmts.User" user "User.Comments")
		(21 "Eco1.User" user "User.Eco1")
		(23 "Eco2.User" user "User.Eco2")
		(25 "Edge.Cuts" user "Board Geometry/Outline")
		(27 "Margin" user)
		(31 "F.CrtYd" user "Package Geometry/Place Bound Top")
		(29 "B.CrtYd" user "Package Geometry/Place Bound Bottom")
		(35 "F.Fab" user "Ref Des/Assembly Top")
		(33 "B.Fab" user "Ref Des/Assembly Bottom")
	)
	(footprint ""
		(layer "F.Cu")
		(at 372.83136 -413.918908 -90)
		(property "Reference" "R3033"
			(at 0 0 270)
			(layer "F.SilkS")
			(hide yes)
			(effects
				(font
					(size 1.27 1.27)
				)
			)
		)
		(property "Value" ""
			(at 0 0 270)
			(layer "F.Fab")
			(effects
				(font
					(size 1.27 1.27)
				)
			)
		)
		(duplicate_pad_numbers_are_jumpers no)
		(fp_line
			(start -0.7874 0.4064)
			(end -0.7874 -0.4064)
			(stroke
				(width 0.1524)
				(type default)
			)
			(layer "F.SilkS")
		)
		(fp_line
			(start 0.7874 0.4064)
			(end -0.7874 0.4064)
			(stroke
				(width 0.1524)
				(type default)
			)
			(layer "F.SilkS")
		)
		(fp_line
			(start -0.7874 -0.4064)
			(end 0.7874 -0.4064)
			(stroke
				(width 0.1524)
				(type default)
			)
			(layer "F.SilkS")
		)
		(fp_line
			(start 0.7874 -0.4064)
			(end 0.7874 0.4064)
			(stroke
				(width 0.1524)
				(type default)
			)
			(layer "F.SilkS")
		)
		(fp_line
			(start -0.67945 0.3048)
			(end -0.67945 -0.305054)
			(stroke
				(width 0.1)
				(type default)
			)
			(layer "F.Fab")
		)
		(fp_line
			(start -0.12065 0.3048)
			(end -0.67945 0.3048)
			(stroke
				(width 0.1)
				(type default)
			)
			(layer "F.Fab")
		)
		(fp_line
			(start 0.120396 0.3048)
			(end 0.120396 0.2794)
			(stroke
				(width 0.1)
				(type default)
			)
			(layer "F.Fab")
		)
		(fp_line
			(start 0.67945 0.3048)
			(end 0.120396 0.3048)
			(stroke
				(width 0.1)
				(type default)
			)
			(layer "F.Fab")
		)
		(fp_line
			(start -0.12065 0.2794)
			(end -0.12065 0.3048)
			(stroke
				(width 0.1)
				(type default)
			)
			(layer "F.Fab")
		)
		(fp_line
			(start 0.120396 0.2794)
			(end -0.12065 0.2794)
			(stroke
				(width 0.1)
				(type default)
			)
			(layer "F.Fab")
		)
		(fp_line
			(start -0.12065 -0.2794)
			(end 0.12065 -0.2794)
			(stroke
				(width 0.1)
				(type default)
			)
			(layer "F.Fab")
		)
		(fp_line
			(start 0.12065 -0.2794)
			(end 0.12065 -0.3048)
			(stroke
				(width 0.1)
				(type default)
			)
			(layer "F.Fab")
		)
		(fp_line
			(start 0.12065 -0.3048)
			(end 0.67945 -0.3048)
			(stroke
				(width 0.1)
				(type default)
			)
			(layer "F.Fab")
		)
		(fp_line
			(start 0.67945 -0.3048)
			(end 0.67945 0.3048)
			(stroke
				(width 0.1)
				(type default)
			)
			(layer "F.Fab")
		)
		(fp_line
			(start -0.67945 -0.305054)
			(end -0.12065 -0.305054)
			(stroke
				(width 0.1)
				(type default)
			)
			(layer "F.Fab")
		)
		(fp_line
			(start -0.12065 -0.305054)
			(end -0.12065 -0.2794)
			(stroke
				(width 0.1)
				(type default)
			)
			(layer "F.Fab")
		)
		(pad "1" smd circle
			(at -0.40005 0 270)
			(size 0 0)
			(layers "F.Cu" "F.Mask" "F.Paste")
			(net "UART_BMC_BIC_RX")
		)
		(pad "2" smd circle
			(at 0.40005 0 270)
			(size 0 0)
			(layers "F.Cu" "F.Mask" "F.Paste")
			(net "UART_BMC_BIC_R_RX")
		)
	)
	(footprint ""
		(layer "F.Cu")
		(at 390.69137 -402.371052 -90)
		(property "Reference" "C946"
			(at 0 0 270)
			(layer "F.SilkS")
			(hide yes)
			(effects
				(font
					(size 1.27 1.27)
				)
			)
		)
		(property "Value" ""
			(at 0 0 270)
			(layer "F.Fab")
			(effects
				(font
					(size 1.27 1.27)
				)
			)
		)
		(duplicate_pad_numbers_are_jumpers no)
		(fp_line
			(start -0.299974 0.150114)
			(end -0.299974 -0.150114)
			(stroke
				(width 0.1)
				(type default)
			)
			(layer "F.Fab")
		)
		(fp_line
			(start 0.299974 0.150114)
			(end -0.299974 0.150114)
			(stroke
				(width 0.1)
				(type default)
			)
			(layer "F.Fab")
		)
		(fp_line
			(start -0.299974 -0.150114)
			(end 0.299974 -0.150114)
			(stroke
				(width 0.1)
				(type default)
			)
			(layer "F.Fab")
		)
		(fp_line
			(start 0.299974 -0.150114)
			(end 0.299974 0.150114)
			(stroke
				(width 0.1)
				(type default)
			)
			(layer "F.Fab")
		)
		(pad "1" smd rect
			(at -0.2667 0 270)
			(size 0.3048 0.381)
			(layers "F.Cu" "F.Mask" "F.Paste")
			(net "P5E_CPU0_PE2_TX_C_DN<9>")
		)
		(pad "2" smd rect
			(at 0.2667 0 270)
			(size 0.3048 0.381)
			(layers "F.Cu" "F.Mask" "F.Paste")
			(net "P5E_CPU0_PE2_TX_DN<9>")
		)
	)
	(footprint ""
		(layer "F.Cu")
		(at 164.64788 -115.026948)
		(property "Reference" "R2346"
			(at 0 0 0)
			(layer "F.SilkS")
			(hide yes)
			(effects
				(font
					(size 1.27 1.27)
				)
			)
		)
		(property "Value" ""
			(at 0 0 0)
			(layer "F.Fab")
			(effects
				(font
					(size 1.27 1.27)
				)
			)
		)
		(duplicate_pad_numbers_are_jumpers no)
		(fp_line
			(start -0.7874 -0.4064)
			(end 0.7874 -0.4064)
			(stroke
				(width 0.1524)
				(type default)
			)
			(layer "F.SilkS")
		)
		(fp_line
			(start -0.7874 0.4064)
			(end -0.7874 -0.4064)
			(stroke
				(width 0.1524)
				(type default)
			)
			(layer "F.SilkS")
		)
		(fp_line
			(start 0.7874 -0.4064)
			(end 0.7874 0.4064)
			(stroke
				(width 0.1524)
				(type default)
			)
			(layer "F.SilkS")
		)
		(fp_line
			(start 0.7874 0.4064)
			(end -0.7874 0.4064)
			(stroke
				(width 0.1524)
				(type default)
			)
			(layer "F.SilkS")
		)
		(fp_line
			(start -0.67945 -0.305054)
			(end -0.12065 -0.305054)
			(stroke
				(width 0.1)
				(type default)
			)
			(layer "F.Fab")
		)
		(fp_line
			(start -0.67945 0.3048)
			(end -0.67945 -0.305054)
			(stroke
				(width 0.1)
				(type default)
			)
			(layer "F.Fab")
		)
		(fp_line
			(start -0.12065 -0.305054)
			(end -0.12065 -0.2794)
			(stroke
				(width 0.1)
				(type default)
			)
			(layer "F.Fab")
		)
		(fp_line
			(start -0.12065 -0.2794)
			(end 0.12065 -0.2794)
			(stroke
				(width 0.1)
				(type default)
			)
			(layer "F.Fab")
		)
		(fp_line
			(start -0.12065 0.2794)
			(end -0.12065 0.3048)
			(stroke
				(width 0.1)
				(type default)
			)
			(layer "F.Fab")
		)
		(fp_line
			(start -0.12065 0.3048)
			(end -0.67945 0.3048)
			(stroke
				(width 0.1)
				(type default)
			)
			(layer "F.Fab")
		)
		(fp_line
			(start 0.120396 0.2794)
			(end -0.12065 0.2794)
			(stroke
				(width 0.1)
				(type default)
			)
			(layer "F.Fab")
		)
		(fp_line
			(start 0.120396 0.3048)
			(end 0.120396 0.2794)
			(stroke
				(width 0.1)
				(type default)
			)
			(layer "F.Fab")
		)
		(fp_line
			(start 0.12065 -0.3048)
			(end 0.67945 -0.3048)
			(stroke
				(width 0.1)
				(type default)
			)
			(layer "F.Fab")
		)
		(fp_line
			(start 0.12065 -0.2794)
			(end 0.12065 -0.3048)
			(stroke
				(width 0.1)
				(type default)
			)
			(layer "F.Fab")
		)
		(fp_line
			(start 0.67945 -0.3048)
			(end 0.67945 0.3048)
			(stroke
				(width 0.1)
				(type default)
			)
			(layer "F.Fab")
		)
		(fp_line
			(start 0.67945 0.3048)
			(end 0.120396 0.3048)
			(stroke
				(width 0.1)
				(type default)
			)
			(layer "F.Fab")
		)
		(pad "1" smd circle
			(at -0.40005 0)
			(size 0 0)
			(layers "F.Cu" "F.Mask" "F.Paste")
			(net "P3V3_AUX")
		)
		(pad "2" smd circle
			(at 0.40005 0)
			(size 0 0)
			(layers "F.Cu" "F.Mask" "F.Paste")
			(net "PWRGD_P5V_AUX_R2")
		)
	)
)
